(kicad_pcb
	(version 20260206)
	(generator "pcbnew")
	(generator_version "10.0")
	(general
		(thickness 1.6)
		(legacy_teardrops no)
	)
	(paper "A4")
	(title_block
		(title "Bryce Canyon_IOM_M2_16342-2_OCP.brd")
		(comment 1 "Bryce Canyon / footprints 227-233 of 1146")
	)
	(layers
		(0 "F.Cu" signal "TOP")
		(4 "In1.Cu" signal "L2GND")
		(6 "In2.Cu" signal "L3")
		(8 "In3.Cu" signal "L4VCC")
		(10 "In4.Cu" signal "L5VCC")
		(12 "In5.Cu" signal "L6")
		(14 "In6.Cu" signal "L7GND")
		(2 "B.Cu" signal "BOTTOM")
		(9 "F.Adhes" user "F.Adhesive")
		(11 "B.Adhes" user "B.Adhesive")
		(13 "F.Paste" user "Package Geometry/Pastemask Top")
		(15 "B.Paste" user "Package Geometry/Pastemask Bottom")
		(5 "F.SilkS" user "Ref Des/Silkscreen Top")
		(7 "B.SilkS" user "Ref Des/Silkscreen Bottom")
		(1 "F.Mask" user "Board Geometry/Soldermask Top")
		(3 "B.Mask" user "Board Geometry/Soldermask Bottom")
		(17 "Dwgs.User" user "User.Drawings")
		(19 "Cmts.User" user "User.Comments")
		(21 "Eco1.User" user "User.Eco1")
		(23 "Eco2.User" user "User.Eco2")
		(25 "Edge.Cuts" user "Board Geometry/Outline")
		(27 "Margin" user)
		(31 "F.CrtYd" user "Package Geometry/Place Bound Top")
		(29 "B.CrtYd" user "Package Geometry/Place Bound Bottom")
		(35 "F.Fab" user "Ref Des/Assembly Top")
		(33 "B.Fab" user "Ref Des/Assembly Bottom")
	)
	(footprint ""
		(layer "F.Cu")
		(at 25.844246 -186.56681 180)
		(property "Reference" "C170"
			(at 0 0 180)
			(layer "F.SilkS")
			(hide yes)
			(effects
				(font
					(size 1.27 1.27)
				)
			)
		)
		(property "Value" "SC10U16V5KX-7-GP-U"
			(at -0.0762 -6.1214 180)
			(unlocked yes)
			(layer "F.Fab")
			(hide yes)
			(effects
				(font
					(size 1.016 1.016)
					(thickness 0.1524)
				)
			)
		)
		(property "Device Type" "C805H58"
			(at -0.0762 -8.1534 180)
			(unlocked yes)
			(layer "F.Fab")
			(hide yes)
			(effects
				(font
					(size 1.016 1.016)
					(thickness 0.1524)
				)
			)
		)
		(duplicate_pad_numbers_are_jumpers no)
		(fp_line
			(start 0.635 0)
			(end -0.635 0)
			(stroke
				(width 0.508)
				(type default)
			)
			(layer "F.SilkS")
		)
		(fp_rect
			(start -0.9652 1.778)
			(end 0.9652 -1.778)
			(stroke
				(width 0)
				(type default)
			)
			(fill no)
			(layer "F.CrtYd")
		)
		(fp_poly
			(pts
				(xy -0.9652 -1.778) (xy 0.9652 -1.778) (xy 0.9652 1.778) (xy -0.9652 1.778)
			)
			(stroke
				(width 0)
				(type default)
			)
			(fill no)
			(layer "F.Fab")
		)
		(pad "1" smd rect
			(at 0 -0.9652 180)
			(size 1.397 1.143)
			(layers "F.Cu" "F.Mask" "F.Paste")
			(net "P12V_STBY_VIN_PU2")
		)
		(pad "2" smd rect
			(at 0 0.9652 180)
			(size 1.397 1.143)
			(layers "F.Cu" "F.Mask" "F.Paste")
			(net "GND")
		)
	)
	(footprint ""
		(layer "F.Cu")
		(at 8.636 -13.081 180)
		(property "Reference" "C31"
			(at 0 0 180)
			(layer "F.SilkS")
			(hide yes)
			(effects
				(font
					(size 1.27 1.27)
				)
			)
		)
		(property "Value" "SC1U16V3KX-5GP"
			(at 0 -2.8194 180)
			(unlocked yes)
			(layer "F.Fab")
			(hide yes)
			(effects
				(font
					(size 1.016 1.016)
					(thickness 0.1524)
				)
			)
		)
		(property "Device Type" "C603H36"
			(at 0 -4.3434 180)
			(unlocked yes)
			(layer "F.Fab")
			(hide yes)
			(effects
				(font
					(size 1.016 1.016)
					(thickness 0.1524)
				)
			)
		)
		(duplicate_pad_numbers_are_jumpers no)
		(fp_line
			(start 0.508 0)
			(end -0.508 0)
			(stroke
				(width 0.2032)
				(type default)
			)
			(layer "F.SilkS")
		)
		(fp_rect
			(start -0.5842 1.3335)
			(end 0.5842 -1.3335)
			(stroke
				(width 0)
				(type default)
			)
			(fill no)
			(layer "F.CrtYd")
		)
		(fp_rect
			(start -0.5842 1.3335)
			(end 0.5842 -1.3335)
			(stroke
				(width 0)
				(type default)
			)
			(fill no)
			(layer "F.Fab")
		)
		(pad "1" smd custom
			(at 0 -0.762 180)
			(size 0.2159 0.2159)
			(layers "F.Cu" "F.Mask" "F.Paste")
			(net "SYS_RST_BTN_IN_N")
			(options
				(clearance outline)
				(anchor circle)
			)
			(primitives
				(gr_poly
					(pts
						(arc
							(start -0.3302 -0.4318)
							(mid -0.402042 -0.402042)
							(end -0.4318 -0.3302)
						)
						(arc
							(start -0.4318 0.3302)
							(mid -0.402042 0.402042)
							(end -0.3302 0.4318)
						)
						(arc
							(start 0.3302 0.4318)
							(mid 0.402042 0.402042)
							(end 0.4318 0.3302)
						)
						(arc
							(start 0.4318 -0.3302)
							(mid 0.402042 -0.402042)
							(end 0.3302 -0.4318)
						)
					)
					(width 0)
					(fill yes)
				)
			)
		)
		(pad "2" smd custom
			(at 0 0.762 180)
			(size 0.2159 0.2159)
			(layers "F.Cu" "F.Mask" "F.Paste")
			(net "GND")
			(options
				(clearance outline)
				(anchor circle)
			)
			(primitives
				(gr_poly
					(pts
						(arc
							(start -0.3302 -0.4318)
							(mid -0.402042 -0.402042)
							(end -0.4318 -0.3302)
						)
						(arc
							(start -0.4318 0.3302)
							(mid -0.402042 0.402042)
							(end -0.3302 0.4318)
						)
						(arc
							(start 0.3302 0.4318)
							(mid 0.402042 0.402042)
							(end 0.4318 0.3302)
						)
						(arc
							(start 0.4318 -0.3302)
							(mid 0.402042 -0.402042)
							(end 0.3302 -0.4318)
						)
					)
					(width 0)
					(fill yes)
				)
			)
		)
	)
	(footprint ""
		(layer "F.Cu")
		(at 10.922 -13.081)
		(property "Reference" "D3"
			(at 0 0 0)
			(layer "F.SilkS")
			(hide yes)
			(effects
				(font
					(size 1.27 1.27)
				)
			)
		)
		(property "Value" "PESD5V0X1UAB-GP"
			(at 0 -4.690618 0)
			(unlocked yes)
			(layer "F.Fab")
			(hide yes)
			(effects
				(font
					(size 1.016 1.016)
					(thickness 0.1524)
				)
			)
		)
		(property "Device Type" "SOD523AKH26"
			(at 0 -6.214618 0)
			(unlocked yes)
			(layer "F.Fab")
			(hide yes)
			(effects
				(font
					(size 1.016 1.016)
					(thickness 0.1524)
				)
			)
		)
		(duplicate_pad_numbers_are_jumpers no)
		(fp_line
			(start -0.5334 -1.4478)
			(end 0.5334 -1.4478)
			(stroke
				(width 0.1524)
				(type default)
			)
			(layer "F.SilkS")
		)
		(fp_line
			(start -0.5334 1.524)
			(end -0.5334 -1.4478)
			(stroke
				(width 0.1524)
				(type default)
			)
			(layer "F.SilkS")
		)
		(fp_line
			(start 0.4064 1.651)
			(end -0.4064 1.651)
			(stroke
				(width 0.4064)
				(type default)
			)
			(layer "F.SilkS")
		)
		(fp_line
			(start 0.5334 -1.4478)
			(end 0.5334 1.524)
			(stroke
				(width 0.1524)
				(type default)
			)
			(layer "F.SilkS")
		)
		(fp_line
			(start 0.5334 1.524)
			(end -0.5334 1.524)
			(stroke
				(width 0.1524)
				(type default)
			)
			(layer "F.SilkS")
		)
		(fp_rect
			(start -0.6096 1.8542)
			(end 0.6096 -1.524)
			(stroke
				(width 0)
				(type default)
			)
			(fill no)
			(layer "F.CrtYd")
		)
		(fp_poly
			(pts
				(xy -0.6096 -1.524) (xy 0.6096 -1.524) (xy 0.6096 1.8542) (xy -0.6096 1.8542)
			)
			(stroke
				(width 0)
				(type default)
			)
			(fill no)
			(layer "F.Fab")
		)
		(pad "A" smd rect
			(at 0 -0.762)
			(size 0.5588 1.016)
			(layers "F.Cu" "F.Mask" "F.Paste")
			(net "GND")
		)
		(pad "K" smd rect
			(at 0 0.762)
			(size 0.5588 1.016)
			(layers "F.Cu" "F.Mask" "F.Paste")
			(net "SYS_RST_BTN_IN_N")
		)
	)
	(footprint ""
		(layer "F.Cu")
		(at 53.371242 -166.953184)
		(property "Reference" "R778"
			(at 0 0 0)
			(layer "F.SilkS")
			(hide yes)
			(effects
				(font
					(size 1.27 1.27)
				)
			)
		)
		(property "Value" "866R2F-GP"
			(at 0.064008 -3.993896 0)
			(unlocked yes)
			(layer "F.Fab")
			(hide yes)
			(effects
				(font
					(size 1.016 1.016)
					(thickness 0.1524)
				)
			)
		)
		(property "Device Type" "R402H16"
			(at 0.064008 -5.517896 0)
			(unlocked yes)
			(layer "F.Fab")
			(hide yes)
			(effects
				(font
					(size 1.016 1.016)
					(thickness 0.1524)
				)
			)
		)
		(duplicate_pad_numbers_are_jumpers no)
		(fp_line
			(start -0.508 -0.9398)
			(end -0.508 0.9398)
			(stroke
				(width 0.1524)
				(type default)
			)
			(layer "F.SilkS")
		)
		(fp_line
			(start 0.508 -0.9398)
			(end -0.508 -0.9398)
			(stroke
				(width 0.1524)
				(type default)
			)
			(layer "F.SilkS")
		)
		(fp_rect
			(start -0.508 0.9398)
			(end 0.508 -0.9398)
			(stroke
				(width 0)
				(type default)
			)
			(fill no)
			(layer "F.CrtYd")
		)
		(fp_rect
			(start -0.508 0.9398)
			(end 0.508 -0.9398)
			(stroke
				(width 0)
				(type default)
			)
			(fill no)
			(layer "F.Fab")
		)
		(pad "1" smd custom
			(at 0 -0.4445)
			(size 0.1397 0.1397)
			(layers "F.Cu" "F.Mask" "F.Paste")
			(net "P2V5_STBY")
			(options
				(clearance outline)
				(anchor circle)
			)
			(primitives
				(gr_poly
					(pts
						(arc
							(start -0.1778 -0.2794)
							(mid -0.249642 -0.249642)
							(end -0.2794 -0.1778)
						)
						(arc
							(start -0.2794 0.1778)
							(mid -0.249642 0.249642)
							(end -0.1778 0.2794)
						)
						(arc
							(start 0.1778 0.2794)
							(mid 0.249642 0.249642)
							(end 0.2794 0.1778)
						)
						(arc
							(start 0.2794 -0.1778)
							(mid 0.249642 -0.249642)
							(end 0.1778 -0.2794)
						)
					)
					(width 0)
					(fill yes)
				)
			)
		)
		(pad "2" smd custom
			(at 0 0.4445)
			(size 0.1397 0.1397)
			(layers "F.Cu" "F.Mask" "F.Paste")
			(net "ADC_P2V5_STBY")
			(options
				(clearance outline)
				(anchor circle)
			)
			(primitives
				(gr_poly
					(pts
						(arc
							(start -0.1778 -0.2794)
							(mid -0.249642 -0.249642)
							(end -0.2794 -0.1778)
						)
						(arc
							(start -0.2794 0.1778)
							(mid -0.249642 0.249642)
							(end -0.1778 0.2794)
						)
						(arc
							(start 0.1778 0.2794)
							(mid 0.249642 0.249642)
							(end 0.2794 0.1778)
						)
						(arc
							(start 0.2794 -0.1778)
							(mid 0.249642 -0.249642)
							(end 0.1778 -0.2794)
						)
					)
					(width 0)
					(fill yes)
				)
			)
		)
	)
	(footprint ""
		(layer "F.Cu")
		(at 153.925016 -11.421618 90)
		(property "Reference" "PU4"
			(at 0 0 90)
			(layer "F.SilkS")
			(hide yes)
			(effects
				(font
					(size 1.27 1.27)
				)
			)
		)
		(property "Value" "TPS53312RGTR-GP"
			(at 4.9784 -6.9342 90)
			(unlocked yes)
			(layer "F.Fab")
			(hide yes)
			(effects
				(font
					(size 1.016 1.016)
					(thickness 0.1524)
				)
			)
		)
		(property "Device Type" "QFN16G3-G1D7H40"
			(at 4.9784 -8.4582 90)
			(unlocked yes)
			(layer "F.Fab")
			(hide yes)
			(effects
				(font
					(size 1.016 1.016)
					(thickness 0.1524)
				)
			)
		)
		(duplicate_pad_numbers_are_jumpers no)
		(fp_line
			(start -1.2446 -2.5146)
			(end -2.5146 -2.5146)
			(stroke
				(width 0.1524)
				(type default)
			)
			(layer "F.SilkS")
		)
		(fp_line
			(start -2.5146 -2.5146)
			(end -2.5146 -1.2446)
			(stroke
				(width 0.1524)
				(type default)
			)
			(layer "F.SilkS")
		)
		(fp_line
			(start -2.262124 -0.750062)
			(end -2.770124 -0.750062)
			(stroke
				(width 0.1524)
				(type default)
			)
			(layer "F.SilkS")
		)
		(fp_line
			(start 2.262124 -0.249936)
			(end 2.770124 -0.249936)
			(stroke
				(width 0.1524)
				(type default)
			)
			(layer "F.SilkS")
		)
		(fp_line
			(start -2.5146 1.2446)
			(end -2.5146 2.5146)
			(stroke
				(width 0.1524)
				(type default)
			)
			(layer "F.SilkS")
		)
		(fp_line
			(start -0.249936 2.262124)
			(end -0.249936 3.024124)
			(stroke
				(width 0.1524)
				(type default)
			)
			(layer "F.SilkS")
		)
		(fp_line
			(start 2.5146 2.5146)
			(end 2.5146 1.2446)
			(stroke
				(width 0.1524)
				(type default)
			)
			(layer "F.SilkS")
		)
		(fp_line
			(start 1.2446 2.5146)
			(end 2.5146 2.5146)
			(stroke
				(width 0.1524)
				(type default)
			)
			(layer "F.SilkS")
		)
		(fp_line
			(start -2.5146 2.5146)
			(end -1.2446 2.5146)
			(stroke
				(width 0.1524)
				(type default)
			)
			(layer "F.SilkS")
		)
		(fp_poly
			(pts
				(xy 2.5146 -2.5146) (xy 1.2446 -2.5146) (xy 2.5146 -1.2446)
			)
			(stroke
				(width 0)
				(type default)
			)
			(fill yes)
			(layer "F.SilkS")
		)
		(fp_rect
			(start -1.4986 1.4986)
			(end 1.4986 -1.4986)
			(stroke
				(width 0)
				(type default)
			)
			(fill no)
			(layer "F.CrtYd")
		)
		(fp_poly
			(pts
				(xy 2.5146 -1.4986) (xy -1.4986 -1.4986) (xy -1.4986 1.4986) (xy 1.4986 1.4986) (xy 1.4986 -1.4859)
				(xy 2.5146 -1.4859) (xy 2.5146 2.5146) (xy -2.5146 2.5146) (xy -2.5146 -2.5146) (xy 2.5146 -2.5146)
			)
			(stroke
				(width 0)
				(type default)
			)
			(fill no)
			(layer "F.CrtYd")
		)
		(fp_rect
			(start -2.5146 2.5146)
			(end 2.5146 -2.5146)
			(stroke
				(width 0)
				(type default)
			)
			(fill no)
			(layer "F.Fab")
		)
		(pad "1" smd rect
			(at 0.750062 -1.550924 90)
			(size 0.3048 0.9144)
			(layers "F.Cu" "F.Mask" "F.Paste")
			(net "P1V8_STBY_VFB")
		)
		(pad "2" smd rect
			(at 0.249936 -1.538224 90)
			(size 0.3048 0.9398)
			(layers "F.Cu" "F.Mask" "F.Paste")
			(net "P1V8_STBY_VRG5")
		)
		(pad "3" smd rect
			(at -0.249936 -1.538224 90)
			(size 0.3048 0.9398)
			(layers "F.Cu" "F.Mask" "F.Paste")
			(net "P1V8_STBY_SS")
		)
		(pad "4" smd rect
			(at -0.750062 -1.550924 90)
			(size 0.3048 0.9144)
			(layers "F.Cu" "F.Mask" "F.Paste")
			(net "AGND_P1V8_STBY")
		)
		(pad "5" smd rect
			(at -1.550924 -0.750062 90)
			(size 0.9144 0.3048)
			(layers "F.Cu" "F.Mask" "F.Paste")
			(net "PWRGD_P1V8_STBY")
		)
		(pad "6" smd rect
			(at -1.538224 -0.249936 90)
			(size 0.9398 0.3048)
			(layers "F.Cu" "F.Mask" "F.Paste")
			(net "P1V8_STBY_EN_R")
		)
		(pad "7" smd rect
			(at -1.538224 0.249936 90)
			(size 0.9398 0.3048)
			(layers "F.Cu" "F.Mask" "F.Paste")
			(net "GND")
		)
		(pad "8" smd rect
			(at -1.550924 0.750062 90)
			(size 0.9144 0.3048)
			(layers "F.Cu" "F.Mask" "F.Paste")
			(net "GND")
		)
		(pad "9" smd rect
			(at -0.750062 1.550924 90)
			(size 0.3048 0.9144)
			(layers "F.Cu" "F.Mask" "F.Paste")
			(net "P1V8_STBY_SW")
		)
		(pad "10" smd rect
			(at -0.249936 1.538224 90)
			(size 0.3048 0.9398)
			(layers "F.Cu" "F.Mask" "F.Paste")
			(net "P1V8_STBY_SW")
		)
		(pad "11" smd rect
			(at 0.249936 1.538224 90)
			(size 0.3048 0.9398)
			(layers "F.Cu" "F.Mask" "F.Paste")
			(net "P1V8_STBY_SW")
		)
		(pad "12" smd rect
			(at 0.750062 1.550924 90)
			(size 0.3048 0.9144)
			(layers "F.Cu" "F.Mask" "F.Paste")
			(net "P1V8_STBY_VBST")
		)
		(pad "13" smd rect
			(at 1.550924 0.750062 90)
			(size 0.9144 0.3048)
			(layers "F.Cu" "F.Mask" "F.Paste")
			(net "P12V_STBY_VIN_PU4")
		)
		(pad "14" smd rect
			(at 1.538224 0.249936 90)
			(size 0.9398 0.3048)
			(layers "F.Cu" "F.Mask" "F.Paste")
			(net "P12V_STBY_VIN_PU4")
		)
		(pad "15" smd rect
			(at 1.538224 -0.249936 90)
			(size 0.9398 0.3048)
			(layers "F.Cu" "F.Mask" "F.Paste")
			(net "P12V_STBY_VCC_PU4")
		)
		(pad "16" smd rect
			(at 1.550924 -0.750062 90)
			(size 0.9144 0.3048)
			(layers "F.Cu" "F.Mask" "F.Paste")
			(net "P1V8_STBY_VO")
		)
		(pad "17" smd rect
			(at 0 0 90)
			(size 1.6764 1.6764)
			(layers "F.Cu" "F.Mask" "F.Paste")
			(net "GND")
		)
	)
	(footprint ""
		(layer "F.Cu")
		(at 23.88108 -186.560714 180)
		(property "Reference" "C171"
			(at 0 0 180)
			(layer "F.SilkS")
			(hide yes)
			(effects
				(font
					(size 1.27 1.27)
				)
			)
		)
		(property "Value" "SC10U16V5KX-7-GP-U"
			(at -0.0762 -6.1214 180)
			(unlocked yes)
			(layer "F.Fab")
			(hide yes)
			(effects
				(font
					(size 1.016 1.016)
					(thickness 0.1524)
				)
			)
		)
		(property "Device Type" "C805H58"
			(at -0.0762 -8.1534 180)
			(unlocked yes)
			(layer "F.Fab")
			(hide yes)
			(effects
				(font
					(size 1.016 1.016)
					(thickness 0.1524)
				)
			)
		)
		(duplicate_pad_numbers_are_jumpers no)
		(fp_line
			(start 0.635 0)
			(end -0.635 0)
			(stroke
				(width 0.508)
				(type default)
			)
			(layer "F.SilkS")
		)
		(fp_rect
			(start -0.9652 1.778)
			(end 0.9652 -1.778)
			(stroke
				(width 0)
				(type default)
			)
			(fill no)
			(layer "F.CrtYd")
		)
		(fp_poly
			(pts
				(xy -0.9652 -1.778) (xy 0.9652 -1.778) (xy 0.9652 1.778) (xy -0.9652 1.778)
			)
			(stroke
				(width 0)
				(type default)
			)
			(fill no)
			(layer "F.Fab")
		)
		(pad "1" smd rect
			(at 0 -0.9652 180)
			(size 1.397 1.143)
			(layers "F.Cu" "F.Mask" "F.Paste")
			(net "P12V_STBY_VIN_PU2")
		)
		(pad "2" smd rect
			(at 0 0.9652 180)
			(size 1.397 1.143)
			(layers "F.Cu" "F.Mask" "F.Paste")
			(net "GND")
		)
	)
	(footprint ""
		(layer "F.Cu")
		(at 92.548456 -161.52368 90)
		(property "Reference" "R27"
			(at 0 0 90)
			(layer "F.SilkS")
			(hide yes)
			(effects
				(font
					(size 1.27 1.27)
				)
			)
		)
		(property "Value" "1MR2F-GP"
			(at 0.064008 -3.993896 90)
			(unlocked yes)
			(layer "F.Fab")
			(hide yes)
			(effects
				(font
					(size 1.016 1.016)
					(thickness 0.1524)
				)
			)
		)
		(property "Device Type" "R402H16"
			(at 0.064008 -5.517896 90)
			(unlocked yes)
			(layer "F.Fab")
			(hide yes)
			(effects
				(font
					(size 1.016 1.016)
					(thickness 0.1524)
				)
			)
		)
		(duplicate_pad_numbers_are_jumpers no)
		(fp_line
			(start 0.508 -0.9398)
			(end -0.508 -0.9398)
			(stroke
				(width 0.1524)
				(type default)
			)
			(layer "F.SilkS")
		)
		(fp_line
			(start -0.508 -0.9398)
			(end -0.508 0.9398)
			(stroke
				(width 0.1524)
				(type default)
			)
			(layer "F.SilkS")
		)
		(fp_rect
			(start -0.508 0.9398)
			(end 0.508 -0.9398)
			(stroke
				(width 0)
				(type default)
			)
			(fill no)
			(layer "F.CrtYd")
		)
		(fp_rect
			(start -0.508 0.9398)
			(end 0.508 -0.9398)
			(stroke
				(width 0)
				(type default)
			)
			(fill no)
			(layer "F.Fab")
		)
		(pad "1" smd custom
			(at 0 -0.4445 90)
			(size 0.1397 0.1397)
			(layers "F.Cu" "F.Mask" "F.Paste")
			(net "USB_HUB_XTAL_IN")
			(options
				(clearance outline)
				(anchor circle)
			)
			(primitives
				(gr_poly
					(pts
						(arc
							(start -0.1778 -0.2794)
							(mid -0.249642 -0.249642)
							(end -0.2794 -0.1778)
						)
						(arc
							(start -0.2794 0.1778)
							(mid -0.249642 0.249642)
							(end -0.1778 0.2794)
						)
						(arc
							(start 0.1778 0.2794)
							(mid 0.249642 0.249642)
							(end 0.2794 0.1778)
						)
						(arc
							(start 0.2794 -0.1778)
							(mid 0.249642 -0.249642)
							(end 0.1778 -0.2794)
						)
					)
					(width 0)
					(fill yes)
				)
			)
		)
		(pad "2" smd custom
			(at 0 0.4445 90)
			(size 0.1397 0.1397)
			(layers "F.Cu" "F.Mask" "F.Paste")
			(net "USB_HUB_XTAL_OUT")
			(options
				(clearance outline)
				(anchor circle)
			)
			(primitives
				(gr_poly
					(pts
						(arc
							(start -0.1778 -0.2794)
							(mid -0.249642 -0.249642)
							(end -0.2794 -0.1778)
						)
						(arc
							(start -0.2794 0.1778)
							(mid -0.249642 0.249642)
							(end -0.1778 0.2794)
						)
						(arc
							(start 0.1778 0.2794)
							(mid 0.249642 0.249642)
							(end 0.2794 0.1778)
						)
						(arc
							(start 0.2794 -0.1778)
							(mid 0.249642 -0.249642)
							(end 0.1778 -0.2794)
						)
					)
					(width 0)
					(fill yes)
				)
			)
		)
	)
)
